%FSTAX25Y25*%
%MOIN*%
%SFA1B1*%

%IPPOS*%
%ADD18C,0.005000*%
%ADD112C,0.008000*%
%ADD113C,0.020000*%
%ADD122C,0.059060*%
%ADD126C,0.016000*%
%ADD128C,0.050000*%
%ADD130C,0.025000*%
%LNtimecard-dc-beta-v1-1*%
%LPD*%
G54D18*
X0264961Y0097623D02*
D01*
X0264826Y0097478*
X0264702Y0097325*
X0264589Y0097163*
X0264487Y0096994*
X0264397Y0096818*
X026432Y0096637*
X0264256Y009645*
X0264205Y0096259*
X0264167Y0096066*
X0264143Y009587*
X0264133Y0095673*
X0264133Y0095624*
X0260885Y0086102D02*
D01*
X0261412Y0086667*
X0261899Y0087269*
X0262343Y0087903*
X0262742Y0088566*
X0263093Y0089256*
X0263396Y0089968*
X0263647Y00907*
X0263848Y0091447*
X0263995Y0092207*
X026409Y0092975*
X026413Y0093748*
X0264133Y0093941*
X0257864Y0083081D02*
D01*
X0257673Y0082876*
X0257497Y0082659*
X0257337Y0082431*
X0257194Y0082191*
X0257067Y0081943*
X0256958Y0081686*
X0256867Y0081422*
X0256795Y0081152*
X0256741Y0080878*
X0256707Y0080601*
X0256693Y0080322*
X0256693Y0080255*
X0256339Y0038389D02*
D01*
X0256398Y0038453*
X0256454Y0038521*
X0256504Y0038593*
X0256549Y0038669*
X0256589Y0038747*
X0256623Y0038828*
X0256652Y0038911*
X0256674Y0038996*
X0256691Y0039082*
X0256693Y0039094*
X0246473Y0028523D02*
D01*
X0246449Y0028497*
X0246427Y002847*
X0246407Y0028441*
X0246389Y0028411*
X0246374Y002838*
X024636Y0028348*
X0246349Y0028315*
X024634Y0028281*
X0246333Y0028247*
X0246329Y0028212*
X0246328Y0028177*
X0246328Y0028142*
X024633Y0028125*
X0242681Y0027559D02*
D01*
X0242712Y0027433*
X0242753Y0027311*
X0242802Y0027191*
X0242859Y0027075*
X0242924Y0026964*
X0242997Y0026857*
X0243077Y0026756*
X0243164Y002666*
X0243257Y0026571*
X0243357Y0026489*
X0243462Y0026413*
X0243572Y0026345*
X0243686Y0026285*
X0243804Y0026233*
X0243926Y002619*
X024405Y0026155*
X0244177Y0026129*
X0244305Y0026111*
X0244433Y0026103*
X0244563Y0026104*
X0244691Y0026113*
X0244819Y0026132*
X0244945Y0026159*
X0245069Y0026196*
X024519Y002624*
X0245308Y0026294*
X0245422Y0026355*
X0245531Y0026424*
X0245635Y00265*
X0245734Y0026584*
X0245826Y0026674*
X0245912Y002677*
X0245991Y0026873*
X0246063Y002698*
X0246127Y0027092*
X0246183Y0027209*
X0246231Y0027329*
X024627Y0027452*
X02463Y0027577*
X0246322Y0027704*
X0246335Y0027833*
X0246339Y0027962*
X0246334Y0028091*
X024633Y0028125*
X0242681Y0027559D02*
D01*
X0242672Y0027592*
X0242661Y0027626*
X0242648Y0027658*
X0242632Y0027689*
X0242615Y0027719*
X0242595Y0027748*
X0242573Y0027776*
X024255Y0027802*
X0242525Y0027826*
X0242498Y0027848*
X024247Y0027868*
X024244Y0027887*
X0242409Y0027903*
X0242377Y0027917*
X0242344Y0027929*
X0242311Y0027938*
X0242276Y0027946*
X0242242Y002795*
X0242207Y0027953*
X0242189Y0027953*
X0263033Y0095624D02*
D01*
X0263026Y0095821*
X0263005Y0096017*
X0262971Y0096211*
X0262923Y0096403*
X0262862Y009659*
X0262788Y0096773*
X0262702Y0096951*
X0262603Y0097122*
X0262493Y0097285*
X0262371Y0097441*
X0262239Y0097587*
X0262205Y0097623*
X0260104Y0086875D02*
D01*
X026058Y0087385*
X0261019Y0087927*
X0261419Y0088499*
X0261779Y0089097*
X0262095Y0089719*
X0262368Y0090362*
X0262595Y0091022*
X0262776Y0091696*
X0262909Y0092381*
X0262994Y0093074*
X0263031Y0093771*
X0263033Y0093946*
X0255372Y0038837D02*
D01*
X0255407Y0038875*
X0255441Y0038916*
X0255471Y0038959*
X0255498Y0039004*
X0255522Y0039051*
X0255543Y00391*
X025556Y003915*
X0255573Y0039201*
X0255583Y0039252*
X025559Y0039305*
X0255593Y0039357*
Y003937*
X0269291Y0079513D02*
D01*
X0269156Y0079368*
X0269032Y0079215*
X0268919Y0079053*
X0268817Y0078884*
X0268727Y0078708*
X026865Y0078527*
X0268586Y007834*
X0268535Y0078149*
X0268497Y0077956*
X0268473Y007776*
X0268463Y0077563*
X0268463Y0077514*
X0265216Y0049094D02*
D01*
X0265743Y0049659*
X026623Y0050261*
X0266674Y0050895*
X0267073Y0051558*
X0267424Y0052248*
X0267727Y005296*
X0267978Y0053692*
X0268179Y0054439*
X0268326Y0055199*
X0268421Y0055967*
X0268461Y005674*
X0268463Y0056933*
X0263376Y0047254D02*
D01*
X0262865Y0046706*
X0262394Y0046125*
X0261965Y0045512*
X026158Y004487*
X026124Y0044203*
X0260947Y0043515*
X0260704Y0042807*
X026051Y0042084*
X0260367Y004135*
X0260276Y0040607*
X0260237Y003986*
X0260236Y0039682*
X0267363Y0077514D02*
D01*
X0267356Y0077711*
X0267335Y0077907*
X0267301Y0078101*
X0267253Y0078293*
X0267192Y007848*
X0267118Y0078663*
X0267032Y0078841*
X0266933Y0079012*
X0266823Y0079175*
X0266701Y0079331*
X0266569Y0079477*
X0266535Y0079513*
X0264435Y0049867D02*
D01*
X0264911Y0050377*
X026535Y0050919*
X026575Y0051491*
X026611Y0052089*
X0266426Y0052711*
X0266699Y0053354*
X0266926Y0054014*
X0267107Y0054688*
X026724Y0055373*
X0267325Y0056066*
X0267362Y0056763*
X0267363Y0056939*
X026259Y0048023D02*
D01*
X0262094Y0047491*
X0261637Y0046927*
X026122Y0046331*
X0260851Y0045717*
D01*
X0260448Y0045079*
X026009Y0044414*
X025978Y0043727*
X0259519Y0043019*
X0259308Y0042295*
X0259147Y0041558*
X0259039Y0040811*
X0259008Y0040483*
D01*
X0259006Y0040448*
X0259006Y0040443*
X0258947Y0032477D02*
D01*
X0258893Y0032367*
X0258847Y0032254*
X0258809Y0032137*
X0258793Y0032075*
D01*
X0258792Y0032074*
Y0032074*
X0258792Y0032074*
Y0032074*
X0258793Y0032074*
X0260464Y0027953D02*
D01*
X026036Y0027949*
X0260258Y0027938*
X0260156Y002792*
X0260056Y0027895*
X0260006Y002788*
D01*
X0259973Y0027868*
X0259941Y0027854*
X025991Y0027837*
X025988Y0027819*
X0259852Y0027798*
X0259825Y0027776*
X02598Y0027752*
X0259777Y0027726*
X0259755Y0027699*
X0259735Y002767*
X0259718Y002764*
X0259702Y0027608*
X0259689Y0027576*
X0259678Y0027543*
X0259674Y0027527*
X0257723Y0029797D02*
D01*
X0257757Y0029801*
X0257791Y0029807*
X0257825Y0029816*
X0257858Y0029827*
X025789Y0029841*
X0257922Y0029856*
X0257951Y0029874*
X025798Y0029894*
X0258007Y0029916*
X0258033Y0029939*
X0258057Y0029965*
X0258079Y0029992*
X0258099Y003002*
X0258116Y0030046*
X0257723Y0029797D02*
D01*
X0257594Y0029781*
X0257467Y0029758*
X0257342Y0029725*
X025722Y0029683*
X0257101Y0029634*
X0256986Y0029576*
X0256874Y002951*
X0256768Y0029436*
X0256667Y0029356*
X0256573Y0029268*
X0256484Y0029174*
X0256402Y0029074*
X0256327Y0028969*
X025626Y0028858*
X0256201Y0028744*
X025615Y0028625*
X0256107Y0028503*
X0256073Y0028379*
X0256048Y0028252*
X0256031Y0028124*
X0256024Y0027995*
X0256025Y0027866*
X0256036Y0027737*
X0256055Y002761*
X0256084Y0027484*
X0256121Y002736*
X0256166Y0027239*
X025622Y0027122*
X0256282Y0027008*
X0256352Y00269*
X0256429Y0026796*
X0256513Y0026698*
X0256604Y0026606*
X0256701Y0026521*
X0256804Y0026443*
X0256912Y0026372*
X0257024Y0026309*
X0257141Y0026253*
X0257261Y0026207*
X0257385Y0026168*
X025751Y0026138*
X0257638Y0026117*
X0257766Y0026105*
X0257896Y0026102*
X0258025Y0026109*
X0258153Y0026124*
X025828Y0026147*
X0258405Y002618*
X0258527Y0026222*
X0258646Y0026271*
X0258761Y0026329*
X0258873Y0026395*
X0258979Y0026469*
X025908Y0026549*
X0259174Y0026637*
X0259263Y0026731*
X0259345Y0026831*
X025942Y0026936*
X0259487Y0027047*
X0259546Y0027161*
X0259597Y002728*
X025964Y0027402*
X0259672Y0027519*
X0282677Y0079513D02*
D01*
X0282542Y0079368*
X0282418Y0079215*
X0282305Y0079053*
X0282203Y0078884*
X0282113Y0078708*
X0282036Y0078527*
X0281972Y007834*
X0281921Y0078149*
X0281883Y0077956*
X0281859Y007776*
X0281849Y0077563*
X0281849Y0077514*
X0279521Y0042926D02*
D01*
X0279899Y0043331*
X0280248Y0043762*
X0280566Y0044217*
X0280852Y0044692*
X0281104Y0045187*
X028132Y0045697*
X0281501Y0046222*
X0281645Y0046758*
X0281751Y0047302*
X0281818Y0047853*
X0281847Y0048407*
X0281849Y0048546*
X0274954Y0038359D02*
D01*
X027493Y0038333*
X0274908Y0038306*
X0274888Y0038277*
X027487Y0038248*
X0274854Y0038216*
X027484Y0038184*
X0274829Y0038151*
X027482Y0038118*
X0274813Y0038084*
X0274809Y0038049*
X0274807Y0038014*
X0274807Y0038005*
X0274803Y0028501D02*
D01*
X0274804Y0028466*
X0274807Y0028431*
X0274813Y0028397*
X0274822Y0028363*
X0274833Y0028329*
X0274846Y0028297*
X0274861Y0028266*
X0274878Y0028236*
X0274882Y0028231*
X0280749Y0077514D02*
D01*
X0280742Y0077711*
X0280721Y0077907*
X0280687Y0078101*
X0280639Y0078293*
X0280578Y007848*
X0280504Y0078663*
X0280418Y0078841*
X0280319Y0079012*
X0280209Y0079175*
X0280087Y0079331*
X0279955Y0079477*
X0279921Y0079513*
X0277102Y0027953D02*
D01*
X0277067Y0027951*
X0277032Y0027948*
X0276997Y0027942*
X0276964Y0027934*
X027693Y0027923*
X0276898Y002791*
X0276866Y0027895*
X0276836Y0027878*
X0276807Y0027859*
X0276779Y0027837*
X0276753Y0027814*
X0276729Y0027789*
X0276706Y0027763*
X0276686Y0027735*
X0276667Y0027705*
X027665Y0027674*
X0276636Y0027643*
X0276624Y002761*
X0276614Y0027576*
X0276611Y0027559*
X0273744Y0026739D02*
D01*
X0273829Y0026657*
X027392Y0026581*
X0274015Y0026512*
X0274116Y002645*
X027422Y0026395*
X0274328Y0026347*
X0274439Y0026307*
X0274553Y0026275*
X0274669Y0026251*
X0274786Y0026235*
X0274904Y0026227*
X0275022Y0026227*
X027514Y0026236*
X0275256Y0026253*
X0275372Y0026278*
X0275485Y0026311*
X0275596Y0026352*
X0275704Y00264*
X0275808Y0026456*
X0275908Y0026519*
X0276003Y0026589*
X0276093Y0026665*
X0276178Y0026747*
X0276257Y0026835*
X0276329Y0026929*
X0276395Y0027027*
X0276454Y002713*
X0276505Y0027236*
X0276549Y0027346*
X0276585Y0027458*
X0276611Y0027559*
X0271304Y0032755D02*
D01*
X0271325Y0032151*
X0271389Y0031551*
X0271494Y0030956*
X027164Y003037*
X0271827Y0029796*
X0272054Y0029236*
X0272319Y0028694*
X0272621Y0028171*
X0272959Y0027671*
X0273331Y0027195*
X0273736Y0026747*
X0273742Y0026741*
X0292685Y0040095D02*
D01*
X0292708Y004012*
X029273Y0040147*
X029275Y0040176*
X0292768Y0040206*
X0292784Y0040237*
X0292798Y0040269*
X0292809Y0040302*
X0292818Y0040335*
X0292825Y004037*
X0292829Y0040404*
X0292831Y0040439*
X0292832Y004045*
Y0083465D02*
D01*
X0292829Y0083541*
X0292821Y0083618*
X0292807Y0083693*
X0292789Y0083768*
X0292765Y0083841*
X0292736Y0083912*
X0292703Y0083981*
X0292664Y0084047*
X0292621Y0084111*
X0292574Y0084172*
X0292523Y0084229*
X029251Y0084242*
X0275944Y0094095D02*
D01*
X0275953Y0093836*
X027598Y0093579*
X0276024Y0093324*
X0276087Y0093074*
X0276167Y0092828*
X0276264Y0092588*
X0276377Y0092356*
X0276506Y0092132*
X0276651Y0091917*
X027681Y0091714*
X0276983Y0091521*
X0277029Y0091475*
X0278961Y0089543D02*
D01*
X0279471Y0089066*
X0280013Y0088627*
X0280585Y0088227*
X0281183Y0087867*
X0281805Y0087551*
X0282448Y0087278*
X0283108Y0087051*
X0283782Y008687*
X0284467Y0086737*
X028516Y0086652*
X0285857Y0086615*
X0286032Y0086614*
X0276772Y0097623D02*
D01*
X0276637Y0097478*
X0276513Y0097325*
X02764Y0097163*
X0276298Y0096994*
X0276208Y0096818*
X0276131Y0096637*
X0276067Y009645*
X0276016Y0096259*
X0275978Y0096066*
X0275954Y009587*
X0275944Y0095673*
X0275944Y0095624*
X0291513Y0085239D02*
D01*
X0291273Y0085462*
X0291018Y0085668*
X029075Y0085856*
X0290469Y0086025*
X0290177Y0086174*
X0289875Y0086302*
X0289565Y0086409*
X0289249Y0086493*
X0288927Y0086556*
X0288602Y0086596*
X0288274Y0086613*
X0288194Y0086614*
X0289764Y0028944D02*
D01*
X0289765Y0028909*
X0289768Y0028874*
X0289774Y002884*
X0289783Y0028806*
X0289794Y0028772*
X0289807Y002874*
X0289822Y0028709*
X0289839Y0028679*
X0289859Y002865*
X028988Y0028622*
X0289904Y0028596*
X028991Y002859*
X0291732Y008206D02*
D01*
X0291723Y0082296*
X0291698Y0082532*
X0291657Y0082765*
X02916Y0082994*
X0291527Y008322*
X0291438Y0083439*
X0291334Y0083652*
X0291216Y0083857*
X0291084Y0084053*
X0290938Y008424*
X029078Y0084416*
X0290739Y0084458*
X0292849Y0027953D02*
D01*
X0292814Y0027951*
X0292779Y0027948*
X0292744Y0027942*
X0292711Y0027934*
X0292677Y0027923*
X0292645Y002791*
X0292613Y0027895*
X0292583Y0027878*
X0292554Y0027859*
X0292526Y0027837*
X02925Y0027814*
X0292476Y0027789*
X0292453Y0027763*
X0292433Y0027735*
X0292414Y0027705*
X0292397Y0027674*
X0292383Y0027643*
X0292371Y002761*
X0292361Y0027576*
X0292357Y0027559*
X0291271Y0040203D02*
D01*
X0291383Y0040414*
X0291481Y0040633*
X0291563Y0040858*
X0291629Y0041089*
X0291679Y0041323*
X0291713Y004156*
X029173Y00418*
X0291732Y0041913*
X0291119Y0040039D02*
D01*
X0291147Y0040059*
X0291173Y0040082*
X0291198Y0040106*
X0291221Y0040132*
X0291243Y004016*
X0291262Y0040189*
X0291271Y0040203*
X0288598Y002749D02*
D01*
X0288635Y002736*
X0288682Y0027234*
X0288738Y0027111*
X0288802Y0026992*
X0288874Y0026878*
X0288954Y002677*
X0289041Y0026667*
X0289135Y0026571*
X0289236Y0026481*
X0289342Y0026399*
X0289455Y0026324*
X0289572Y0026257*
X0289693Y0026199*
X0289819Y0026149*
X0289947Y0026108*
X0290078Y0026076*
X0290211Y0026054*
X0290345Y002604*
X029048Y0026036*
X0290614Y0026042*
X0290748Y0026057*
X0290881Y0026081*
X0291012Y0026114*
X0291139Y0026157*
X0291264Y0026208*
X0291385Y0026268*
X0291501Y0026336*
X0291613Y0026412*
X0291718Y0026495*
X0291818Y0026586*
X0291911Y0026684*
X0291997Y0026787*
X0292076Y0026897*
X0292146Y0027012*
X0292209Y0027131*
X0292263Y0027254*
X0292308Y0027381*
X0292345Y0027511*
X0292357Y0027559*
X0274844Y0094089D02*
D01*
X0274855Y0093754*
X027489Y0093422*
X0274948Y0093092*
X0275029Y0092768*
X0275132Y009245*
X0275258Y009214*
X0275404Y0091839*
X0275572Y009155*
X0275758Y0091272*
X0275964Y0091009*
X0276188Y009076*
X0276247Y0090701*
X0274844Y0095624D02*
D01*
X0274837Y0095821*
X0274816Y0096017*
X0274782Y0096211*
X0274734Y0096403*
X0274673Y009659*
X0274599Y0096773*
X0274513Y0096951*
X0274414Y0097122*
X0274304Y0097285*
X0274182Y0097441*
X027405Y0097587*
X0274016Y0097623*
X0291114Y0040036D02*
D01*
X0290788Y0039797*
X0290479Y0039536*
X029019Y0039255*
X0289921Y0038954*
X0289674Y0038634*
X0289449Y0038299*
X0289249Y0037948*
X0289073Y0037585*
X0288923Y003721*
X02888Y0036826*
X0288704Y0036433*
X0288635Y0036036*
X0288595Y0035634*
X0288583Y003526*
X0290739Y0084458D02*
D01*
X0290554Y0084629*
X0290359Y0084788*
X0290153Y0084932*
X0289937Y0085062*
X0289713Y0085176*
X0289481Y0085274*
X0289243Y0085356*
X0289Y0085421*
X0288753Y0085469*
X0288503Y00855*
X0288251Y0085513*
X0288189Y0085514*
X0288583Y0027614D02*
D01*
X0288584Y0027579*
X0288587Y0027544*
X0288593Y002751*
X0288598Y002749*
X0278186Y0088763D02*
D01*
X0278752Y0088235*
X0279353Y0087747*
X0279987Y0087303*
X0280651Y0086905*
X0281341Y0086553*
X0282053Y0086251*
X0282785Y0085999*
X0283533Y0085798*
X0284293Y0085651*
X0285061Y0085556*
X0285834Y0085516*
X0286028Y0085514*
X0258947Y0032477D02*
D01*
X0258962Y0032508*
X0258975Y003254*
X0258986Y0032573*
X0258994Y0032607*
X0259001Y0032642*
X0259004Y0032676*
X0259006Y0032711*
X0259006Y0032712*
X0258332Y0030388D02*
D01*
X025835Y0030417*
X0258367Y0030447*
X0258382Y0030479*
X0258394Y0030512*
X0258405Y0030545*
X0258408Y0030554*
X0258332Y0030388D02*
D01*
X0258159Y003012*
X0258116Y0030046*
X0257874Y0027953D02*
D01*
X0258257Y0028364*
X0258612Y0028802*
X0258935Y0029263*
X02591Y0029528*
X0260236Y0037653D02*
D01*
X0260237Y00376*
X0260243Y0037548*
X0260252Y0037497*
X0260265Y0037446*
X0260281Y0037396*
X02603Y0037347*
X0260323Y00373*
X0260349Y0037255*
X0260379Y0037212*
X0260411Y003717*
X0260446Y0037132*
X0260484Y0037095*
X0260524Y0037061*
X0260566Y0037031*
X0260611Y0037003*
X0260657Y0036978*
X0260705Y0036957*
X0260754Y0036939*
X0260804Y0036925*
X0260855Y0036914*
X0260907Y0036907*
X0260959Y0036903*
X0260986Y0036903*
X0261609Y0035403D02*
D01*
X0261661Y0035404*
X0261713Y003541*
X0261764Y0035419*
X0261815Y0035432*
X0261865Y0035448*
X0261914Y0035467*
X0261961Y003549*
X0262006Y0035516*
X0262049Y0035546*
X0262091Y0035578*
X0262129Y0035613*
X0262166Y0035651*
X02622Y0035691*
X026223Y0035733*
X0262258Y0035778*
X0262283Y0035824*
X0262304Y0035872*
X0262322Y0035921*
X0262336Y0035971*
X0262347Y0036022*
X0262354Y0036074*
X0262358Y0036126*
Y0036179*
X0262354Y0036231*
X0262347Y0036283*
X0262336Y0036334*
X0262322Y0036384*
X0262304Y0036433*
X0262283Y0036481*
X0262258Y0036528*
X026223Y0036572*
X02622Y0036614*
X0262166Y0036654*
X0262129Y0036692*
X0262091Y0036727*
X0262049Y0036759*
X0262006Y0036789*
X0261961Y0036815*
X0261914Y0036838*
X0261865Y0036857*
X0261815Y0036873*
X0261764Y0036886*
X0261713Y0036895*
X0261661Y0036901*
X0261609Y0036903*
X0260756Y0035403D02*
D01*
X0260703Y0035401*
X0260651Y0035395*
X02606Y0035386*
X0260549Y0035373*
X0260499Y0035357*
X026045Y0035338*
X0260403Y0035315*
X0260358Y0035289*
X0260315Y0035259*
X0260273Y0035227*
X0260235Y0035192*
X0260198Y0035154*
X0260164Y0035114*
X0260134Y0035072*
X0260106Y0035028*
X0260081Y0034981*
X026006Y0034933*
X0260042Y0034884*
X0260028Y0034834*
X0260017Y0034783*
X026001Y0034731*
X0260006Y0034679*
Y0034626*
X026001Y0034574*
X0260017Y0034522*
X0260028Y0034471*
X0260042Y0034421*
X026006Y0034372*
X0260081Y0034324*
X0260106Y0034278*
X0260134Y0034233*
X0260164Y0034191*
X0260198Y0034151*
X0260235Y0034113*
X0260273Y0034078*
X0260315Y0034046*
X0260358Y0034016*
X0260403Y003399*
X026045Y0033967*
X0260499Y0033948*
X0260549Y0033932*
X02606Y0033919*
X0260651Y003391*
X0260703Y0033904*
X0260756Y0033903*
X0261973Y0032403D02*
D01*
X0262025Y0032404*
X0262077Y003241*
X0262128Y0032419*
X0262179Y0032432*
X0262229Y0032448*
X0262278Y0032467*
X0262325Y003249*
X026237Y0032516*
X0262413Y0032546*
X0262455Y0032578*
X0262493Y0032613*
X026253Y0032651*
X0262564Y0032691*
X0262594Y0032733*
X0262622Y0032778*
X0262647Y0032824*
X0262668Y0032872*
X0262686Y0032921*
X02627Y0032971*
X0262711Y0033022*
X0262718Y0033074*
X0262722Y0033126*
Y0033179*
X0262718Y0033231*
X0262711Y0033283*
X02627Y0033334*
X0262686Y0033384*
X0262668Y0033433*
X0262647Y0033481*
X0262622Y0033528*
X0262594Y0033572*
X0262564Y0033614*
X026253Y0033654*
X0262493Y0033692*
X0262455Y0033727*
X0262413Y0033759*
X026237Y0033789*
X0262325Y0033815*
X0262278Y0033838*
X0262229Y0033857*
X0262179Y0033873*
X0262128Y0033886*
X0262077Y0033895*
X0262025Y0033901*
X0261973Y0033903*
X0260491Y0032403D02*
D01*
X0260438Y0032401*
X0260386Y0032395*
X0260335Y0032386*
X0260284Y0032373*
X0260234Y0032357*
X0260185Y0032338*
X0260138Y0032315*
X0260093Y0032289*
X026005Y0032259*
X0260008Y0032227*
X025997Y0032192*
X0259933Y0032154*
X0259899Y0032114*
X0259869Y0032072*
X0259841Y0032028*
X0259816Y0031981*
X0259795Y0031933*
X0259777Y0031884*
X0259764Y0031837*
X02591Y0029528D02*
D01*
X0259129Y0029577*
X0259158Y0029627*
X0259186Y0029677*
X0259215Y0029727*
X0259243Y0029778*
X0290912Y0036694D02*
D01*
X0290913Y0036641*
X0290919Y0036589*
X0290928Y0036538*
X0290941Y0036487*
X0290957Y0036437*
X0290976Y0036388*
X0290999Y0036341*
X0291025Y0036296*
X0291055Y0036253*
X0291087Y0036211*
X0291122Y0036173*
X029116Y0036136*
X02912Y0036102*
X0291242Y0036072*
X0291287Y0036044*
X0291333Y0036019*
X0291381Y0035998*
X029143Y003598*
X029148Y0035966*
X0291531Y0035955*
X0291583Y0035948*
X0291635Y0035944*
X0291662Y0035944*
Y0034444D02*
D01*
X0291714Y0034445*
X0291766Y0034451*
X0291817Y003446*
X0291868Y0034473*
X0291918Y0034489*
X0291967Y0034508*
X0292014Y0034531*
X0292059Y0034557*
X0292102Y0034587*
X0292144Y0034619*
X0292182Y0034654*
X0292219Y0034692*
X0292253Y0034732*
X0292283Y0034774*
X0292311Y0034819*
X0292336Y0034865*
X0292357Y0034913*
X0292375Y0034962*
X0292389Y0035012*
X02924Y0035063*
X0292407Y0035115*
X0292411Y0035167*
Y003522*
X0292407Y0035272*
X02924Y0035324*
X0292389Y0035375*
X0292375Y0035425*
X0292357Y0035474*
X0292336Y0035522*
X0292311Y0035569*
X0292283Y0035613*
X0292253Y0035655*
X0292219Y0035695*
X0292182Y0035733*
X0292144Y0035768*
X0292102Y00358*
X0292059Y003583*
X0292014Y0035856*
X0291967Y0035879*
X0291918Y0035898*
X0291868Y0035914*
X0291817Y0035927*
X0291766Y0035936*
X0291714Y0035942*
X0291662Y0035944*
X0290333Y0034444D02*
D01*
X029028Y0034442*
X0290228Y0034436*
X0290177Y0034427*
X0290126Y0034414*
X0290076Y0034398*
X0290027Y0034379*
X028998Y0034356*
X0289935Y003433*
X0289892Y00343*
X028985Y0034268*
X0289812Y0034233*
X0289775Y0034195*
X0289741Y0034155*
X0289711Y0034113*
X0289683Y0034069*
X0289658Y0034022*
X0289637Y0033974*
X0289619Y0033925*
X0289605Y0033875*
X0289594Y0033824*
X0289587Y0033772*
X0289583Y003372*
Y0033667*
X0289587Y0033615*
X0289594Y0033563*
X0289605Y0033512*
X0289619Y0033462*
X0289637Y0033413*
X0289658Y0033365*
X0289683Y0033319*
X0289711Y0033274*
X0289741Y0033232*
X0289775Y0033192*
X0289812Y0033154*
X028985Y0033119*
X0289892Y0033087*
X0289935Y0033057*
X028998Y0033031*
X0290027Y0033008*
X0290076Y0032989*
X0290126Y0032973*
X0290177Y003296*
X0290228Y0032951*
X029028Y0032945*
X0290333Y0032944*
X0291501Y0031444D02*
D01*
X0291553Y0031445*
X0291605Y0031451*
X0291656Y003146*
X0291707Y0031473*
X0291757Y0031489*
X0291806Y0031508*
X0291853Y0031531*
X0291898Y0031557*
X0291941Y0031587*
X0291983Y0031619*
X0292021Y0031654*
X0292058Y0031692*
X0292092Y0031732*
X0292122Y0031774*
X029215Y0031819*
X0292175Y0031865*
X0292196Y0031913*
X0292214Y0031962*
X0292228Y0032012*
X0292239Y0032063*
X0292246Y0032115*
X029225Y0032167*
Y003222*
X0292246Y0032272*
X0292239Y0032324*
X0292228Y0032375*
X0292214Y0032425*
X0292196Y0032474*
X0292175Y0032522*
X029215Y0032569*
X0292122Y0032613*
X0292092Y0032655*
X0292058Y0032695*
X0292021Y0032733*
X0291983Y0032768*
X0291941Y00328*
X0291898Y003283*
X0291853Y0032856*
X0291806Y0032879*
X0291757Y0032898*
X0291707Y0032914*
X0291656Y0032927*
X0291605Y0032936*
X0291553Y0032942*
X0291501Y0032944*
X0290514Y0031444D02*
D01*
X0290461Y0031442*
X0290409Y0031436*
X0290358Y0031427*
X0290307Y0031414*
X0290257Y0031398*
X0290208Y0031379*
X0290161Y0031356*
X0290116Y003133*
X0290073Y00313*
X0290031Y0031268*
X0289993Y0031233*
X0289956Y0031195*
X0289922Y0031155*
X0289892Y0031113*
X0289864Y0031069*
X0289839Y0031022*
X0289818Y0030974*
X02898Y0030925*
X0289786Y0030875*
X0289775Y0030824*
X0289768Y0030772*
X0289764Y003072*
X0289764Y0030694*
X027379Y0038751D02*
D01*
X0273386Y0038318*
X0273013Y0037858*
X0272673Y0037373*
X0272368Y0036866*
X0272099Y0036338*
X0271867Y0035793*
X0271674Y0035234*
X0271521Y0034662*
X0271408Y0034081*
X0271335Y0033493*
X0271304Y0032902*
X0271304Y0032755*
X0274056Y0034812D02*
D01*
X0274108Y0034813*
X027416Y0034819*
X0274211Y0034828*
X0274262Y0034841*
X0274312Y0034857*
X0274361Y0034876*
X0274408Y0034899*
X0274453Y0034925*
X0274496Y0034955*
X0274538Y0034987*
X0274576Y0035022*
X0274613Y003506*
X0274647Y00351*
X0274677Y0035142*
X0274705Y0035187*
X027473Y0035233*
X0274751Y0035281*
X0274769Y003533*
X0274783Y003538*
X0274794Y0035431*
X0274801Y0035483*
X0274805Y0035535*
X0274806Y0035561*
X0273393Y0034812D02*
D01*
X027334Y003481*
X0273288Y0034804*
X0273237Y0034795*
X0273186Y0034782*
X0273136Y0034766*
X0273087Y0034747*
X027304Y0034724*
X0272995Y0034698*
X0272952Y0034668*
X027291Y0034636*
X0272872Y0034601*
X0272835Y0034563*
X0272801Y0034523*
X0272771Y0034481*
X0272743Y0034437*
X0272718Y003439*
X0272697Y0034342*
X0272679Y0034293*
X0272665Y0034243*
X0272654Y0034192*
X0272647Y003414*
X0272643Y0034088*
Y0034035*
X0272647Y0033983*
X0272654Y0033931*
X0272665Y003388*
X0272679Y003383*
X0272697Y0033781*
X0272718Y0033733*
X0272743Y0033687*
X0272771Y0033642*
X0272801Y00336*
X0272835Y003356*
X0272872Y0033522*
X027291Y0033487*
X0272952Y0033455*
X0272995Y0033425*
X027304Y0033399*
X0273087Y0033376*
X0273136Y0033357*
X0273186Y0033341*
X0273237Y0033328*
X0273288Y0033319*
X027334Y0033313*
X0273393Y0033312*
X0275055Y0031812D02*
D01*
X0275107Y0031813*
X0275159Y0031819*
X027521Y0031828*
X0275261Y0031841*
X0275311Y0031857*
X027536Y0031876*
X0275407Y0031899*
X0275452Y0031925*
X0275495Y0031955*
X0275537Y0031987*
X0275575Y0032022*
X0275612Y003206*
X0275646Y00321*
X0275676Y0032142*
X0275704Y0032187*
X0275729Y0032233*
X027575Y0032281*
X0275768Y003233*
X0275782Y003238*
X0275793Y0032431*
X02758Y0032483*
X0275804Y0032535*
Y0032588*
X02758Y003264*
X0275793Y0032692*
X0275782Y0032743*
X0275768Y0032793*
X027575Y0032842*
X0275729Y003289*
X0275704Y0032937*
X0275676Y0032981*
X0275646Y0033023*
X0275612Y0033063*
X0275575Y0033101*
X0275537Y0033136*
X0275495Y0033168*
X0275452Y0033198*
X0275407Y0033224*
X027536Y0033247*
X0275311Y0033266*
X0275261Y0033282*
X027521Y0033295*
X0275159Y0033304*
X0275107Y003331*
X0275055Y0033312*
X0273392Y0031812D02*
D01*
X0273339Y003181*
X0273287Y0031804*
X0273236Y0031795*
X0273185Y0031782*
X0273135Y0031766*
X0273086Y0031747*
X0273039Y0031724*
X0272994Y0031698*
X0272951Y0031668*
X0272909Y0031636*
X0272871Y0031601*
X0272834Y0031563*
X02728Y0031523*
X027277Y0031481*
X0272742Y0031437*
X0272717Y003139*
X0272696Y0031342*
X0272678Y0031293*
X0272664Y0031243*
X0272653Y0031192*
X0272646Y003114*
X0272642Y0031088*
Y0031035*
X0272646Y0030983*
X0272653Y0030931*
X0272664Y003088*
X0272678Y003083*
X0272696Y0030781*
X0272717Y0030733*
X0272742Y0030687*
X027277Y0030642*
X02728Y00306*
X0272834Y003056*
X0272871Y0030522*
X0272909Y0030487*
X0272951Y0030455*
X0272994Y0030425*
X0273039Y0030399*
X0273086Y0030376*
X0273135Y0030357*
X0273185Y0030341*
X0273236Y0030328*
X0273287Y0030319*
X0273339Y0030313*
X0273392Y0030312*
X0274804Y0029561D02*
D01*
X0274802Y0029613*
X0274796Y0029665*
X0274787Y0029716*
X0274774Y0029767*
X0274758Y0029817*
X0274739Y0029866*
X0274716Y0029913*
X027469Y0029958*
X027466Y0030001*
X0274628Y0030043*
X0274593Y0030081*
X0274555Y0030118*
X0274515Y0030152*
X0274473Y0030182*
X0274429Y003021*
X0274382Y0030235*
X0274334Y0030256*
X0274285Y0030274*
X0274235Y0030288*
X0274184Y0030299*
X0274132Y0030306*
X027408Y003031*
X0274054Y0030312*
X0251543Y0036068D02*
D01*
X0251581Y0036032*
X0251621Y0035999*
X0251664Y0035969*
X0251709Y0035942*
X0251756Y0035918*
X0251804Y0035898*
X0251853Y0035881*
X0251904Y0035867*
X0251955Y0035857*
X0252007Y0035851*
X0252059Y0035848*
X0252112Y0035849*
X0252164Y0035854*
X0252216Y0035862*
X0252266Y0035874*
X0252317Y0035889*
X0252365Y0035908*
X0252413Y003593*
X0252459Y0035955*
X0252502Y0035984*
X0252544Y0036015*
X0252584Y0036049*
X0252604Y0036068*
X0251543D02*
D01*
X0251504Y0036103*
X0251464Y0036136*
X0251421Y0036166*
X0251376Y0036193*
X0251329Y0036217*
X0251281Y0036237*
X0251232Y0036254*
X0251181Y0036268*
X025113Y0036278*
X0251078Y0036284*
X0251026Y0036287*
X0250973Y0036286*
X0250921Y0036281*
X0250869Y0036273*
X0250819Y0036261*
X0250768Y0036246*
X025072Y0036227*
X0250672Y0036205*
X0250626Y003618*
X0250583Y0036151*
X0250541Y003612*
X0250501Y0036086*
X0250482Y0036068*
D01*
X0250446Y0036029*
X0250413Y0035989*
X0250383Y0035946*
X0250356Y0035901*
X0250332Y0035854*
X0250312Y0035806*
X0250295Y0035757*
X0250281Y0035706*
X0250271Y0035655*
X0250265Y0035603*
X0250262Y0035551*
X0250263Y0035498*
X0250268Y0035446*
X0250276Y0035394*
X0250288Y0035344*
X0250303Y0035293*
X0250322Y0035245*
X0250344Y0035197*
X0250369Y0035151*
X0250398Y0035108*
X0250429Y0035066*
X0250463Y0035026*
X0250482Y0035008*
Y0033947D02*
D01*
X0250517Y0033985*
X025055Y0034025*
X025058Y0034068*
X0250607Y0034113*
X0250631Y003416*
X0250651Y0034208*
X0250668Y0034257*
X0250682Y0034308*
X0250692Y0034359*
X0250698Y0034411*
X0250701Y0034463*
X02507Y0034516*
X0250695Y0034568*
X0250687Y003462*
X0250675Y003467*
X025066Y0034721*
X0250641Y0034769*
X0250619Y0034817*
X0250594Y0034863*
X0250565Y0034906*
X0250534Y0034948*
X02505Y0034988*
X0250482Y0035008*
X0249422Y0033947D02*
D01*
X024946Y0033911*
X02495Y0033878*
X0249543Y0033848*
X0249588Y0033821*
X0249635Y0033797*
X0249683Y0033777*
X0249732Y003376*
X0249783Y0033746*
X0249834Y0033736*
X0249886Y003373*
X0249938Y0033727*
X0249991Y0033728*
X0250043Y0033733*
X0250095Y0033741*
X0250145Y0033753*
X0250196Y0033768*
X0250244Y0033787*
X0250292Y0033809*
X0250338Y0033834*
X0250381Y0033863*
X0250423Y0033894*
X0250463Y0033928*
X0250482Y0033947*
X0249175Y0034194D02*
D01*
X0249136Y0034229*
X0249096Y0034262*
X0249053Y0034292*
X0249008Y0034319*
X0248961Y0034343*
X0248913Y0034363*
X0248864Y003438*
X0248813Y0034394*
X0248762Y0034404*
X024871Y003441*
X0248658Y0034413*
X0248605Y0034412*
X0248553Y0034407*
X0248501Y0034399*
X0248451Y0034387*
X02484Y0034372*
X0248352Y0034353*
X0248304Y0034331*
X0248258Y0034306*
X0248215Y0034277*
X0248173Y0034246*
X0248133Y0034212*
X0248114Y0034194*
D01*
X0248078Y0034155*
X0248045Y0034115*
X0248015Y0034072*
X0247988Y0034027*
X0247964Y003398*
X0247944Y0033932*
X0247927Y0033883*
X0247913Y0033832*
X0247903Y0033781*
X0247897Y0033729*
X0247894Y0033677*
X0247895Y0033624*
X02479Y0033572*
X0247908Y003352*
X024792Y003347*
X0247935Y0033419*
X0247954Y0033371*
X0247976Y0033323*
X0248001Y0033277*
X024803Y0033234*
X0248061Y0033192*
X0248095Y0033152*
X0248114Y0033133*
X0248361Y0031826D02*
D01*
X0248396Y0031864*
X0248429Y0031904*
X0248459Y0031947*
X0248486Y0031992*
X024851Y0032039*
X024853Y0032087*
X0248547Y0032136*
X0248561Y0032187*
X0248571Y0032238*
X0248577Y003229*
X024858Y0032342*
X0248579Y0032395*
X0248574Y0032447*
X0248566Y0032499*
X0248554Y0032549*
X0248539Y00326*
X024852Y0032648*
X0248498Y0032696*
X0248473Y0032742*
X0248444Y0032785*
X0248413Y0032827*
X0248379Y0032867*
X0248361Y0032886*
X0247301Y0031826D02*
D01*
X0247339Y003179*
X0247379Y0031757*
X0247422Y0031727*
X0247467Y00317*
X0247514Y0031676*
X0247562Y0031656*
X0247611Y0031639*
X0247662Y0031625*
X0247713Y0031615*
X0247765Y0031609*
X0247817Y0031606*
X024787Y0031607*
X0247922Y0031612*
X0247974Y003162*
X0248024Y0031632*
X0248075Y0031647*
X0248123Y0031666*
X0248171Y0031688*
X0248217Y0031713*
X024826Y0031742*
X0248302Y0031773*
X0248342Y0031807*
X0248361Y0031826*
X0246971Y0032155D02*
D01*
X0246932Y003219*
X0246892Y0032223*
X0246849Y0032253*
X0246804Y003228*
X0246757Y0032304*
X0246709Y0032324*
X024666Y0032341*
X0246609Y0032355*
X0246558Y0032365*
X0246506Y0032371*
X0246454Y0032374*
X0246401Y0032373*
X0246349Y0032368*
X0246297Y003236*
X0246247Y0032348*
X0246196Y0032333*
X0246148Y0032314*
X02461Y0032292*
X0246054Y0032267*
X0246011Y0032238*
X0245969Y0032207*
X0245929Y0032173*
X024591Y0032155*
D01*
X0245874Y0032116*
X0245841Y0032076*
X0245811Y0032033*
X0245784Y0031988*
X024576Y0031941*
X024574Y0031893*
X0245723Y0031844*
X0245709Y0031793*
X0245699Y0031742*
X0245693Y003169*
X024569Y0031638*
X0245691Y0031585*
X0245696Y0031533*
X0245704Y0031481*
X0245716Y0031431*
X0245731Y003138*
X024575Y0031332*
X0245772Y0031284*
X0245797Y0031238*
X0245826Y0031195*
X0245857Y0031153*
X0245891Y0031113*
X024591Y0031095*
X024624Y0029704D02*
D01*
X0246275Y0029742*
X0246308Y0029782*
X0246338Y0029825*
X0246365Y002987*
X0246389Y0029917*
X0246409Y0029965*
X0246426Y0030014*
X024644Y0030065*
X024645Y0030116*
X0246456Y0030168*
X0246459Y003022*
X0246458Y0030273*
X0246453Y0030325*
X0246445Y0030377*
X0246433Y0030427*
X0246418Y0030478*
X0246399Y0030526*
X0246377Y0030574*
X0246352Y003062*
X0246323Y0030663*
X0246292Y0030705*
X0246258Y0030745*
X024624Y0030765*
X027874Y0043701D02*
D01*
X0279066Y0044051*
X0279367Y0044423*
X0279642Y0044815*
X0279888Y0045225*
X0280106Y0045652*
X0280293Y0046092*
X0280449Y0046545*
X0280573Y0047008*
X0280664Y0047478*
X0280722Y0047953*
X0280747Y0048431*
X0280749Y0048551*
X0257085Y0083856D02*
D01*
X0256842Y0083596*
X0256618Y0083319*
X0256415Y0083028*
X0256231Y0082723*
X025607Y0082407*
X0255931Y008208*
X0255815Y0081743*
X0255723Y00814*
X0255656Y0081051*
X0255612Y0080698*
X0255594Y0080343*
X0255593Y0080255*
X0264961Y0097623D02*
Y0097638D01*
Y0097623D02*
D01*
X0264133Y0093941D02*
Y0095624D01*
X0257864Y0083081D02*
X0260885Y0086101D01*
X0257864Y0083081D02*
D01*
X0256693Y0039094D02*
Y0080255D01*
Y0039094D02*
D01*
X0246473Y0028523D02*
X0256339Y0038389D01*
X024633Y0028125D02*
D01*
X0242189Y0027953D02*
D01*
X0241339D02*
X0242189D01*
X0263033Y0093946D02*
Y0095624D01*
X0262205Y0097623D02*
Y0097638D01*
X0257085Y0083856D02*
X0260104Y0086875D01*
X0254359Y0037824D02*
X0255372Y0038836D01*
X0269291Y0079513D02*
Y0079528D01*
X0268463Y0056933D02*
Y0077514D01*
X0263376Y0047254D02*
X0265216Y0049094D01*
X0263376Y0047254D02*
D01*
X0266535Y0079513D02*
Y0079528D01*
X0267363Y0056939D02*
Y0077514D01*
X026259Y0048023D02*
X0264435Y0049867D01*
X0260851Y0045717D02*
D01*
X0259008Y0040483D02*
D01*
X0259006Y0032712D02*
Y0040443D01*
X0258793Y0032074D02*
Y0032075D01*
X0258408Y0030554D02*
X0258793Y0032074D01*
X0260464Y0027953D02*
X0261024D01*
X0260006Y002788D02*
D01*
X0259672Y0027519D02*
X0259674Y0027527D01*
X0257723Y0029797D02*
D01*
X0282677Y0079513D02*
Y0079528D01*
X0281849Y0048546D02*
Y0077514D01*
X0274954Y0038359D02*
X0279521Y0042926D01*
X0274807Y0038005D02*
D01*
X0274882Y0028231D02*
D01*
X0274803Y0028501D02*
D01*
X0279921Y0079513D02*
Y0079528D01*
X0280749Y0048551D02*
Y0077514D01*
X0277102Y0027953D02*
X0277953D01*
X0273742Y0026741D02*
X0273744Y0026739D01*
X0292832Y004045D02*
Y0083465D01*
X0292685Y0040095D02*
D01*
X0292643Y0040053D02*
X0292685Y0040095D01*
X0291513Y0085239D02*
X029251Y0084242D01*
X0286032Y0086614D02*
X0288194D01*
X0277029Y0091475D02*
X0278961Y0089543D01*
X0276772Y0097623D02*
Y0097638D01*
X0275944Y0094095D02*
Y0095624D01*
X028991Y002859D02*
D01*
X0291732Y004192D02*
Y008206D01*
Y0041913D02*
Y004192D01*
X0292849Y0027953D02*
X0293701D01*
X0291271Y0040203D02*
D01*
X0291114Y0040036D02*
X0291119Y0040039D01*
X0292357Y0027559D02*
D01*
X0274844Y0094089D02*
Y0095624D01*
X0274016Y0097623D02*
Y0097638D01*
X0288583Y0027614D02*
Y0035255D01*
X0286028Y0085514D02*
X0288189D01*
X0288583Y003526D02*
Y0035255D01*
X0288189Y0085514D02*
D01*
X0260236Y0038976D02*
D01*
Y0038726D02*
Y0038976D01*
Y0037653D02*
Y0038726D01*
X0260986Y0036903D02*
X0261609D01*
X0260756Y0035403D02*
X0261609D01*
X0260756Y0033903D02*
X0261973D01*
X0260491Y0032403D02*
X0261973D01*
X0259764Y0031837D02*
D01*
X0259243Y0029778D02*
X0259764Y0031837D01*
X0260236Y0038976D02*
Y0039682D01*
X0292393Y0039803D02*
X0292643Y0040053D01*
X0291058Y0038469D02*
X0292393Y0039803D01*
X0290912Y0038115D02*
X0291058Y0038469D01*
X0290912Y0036694D02*
Y0038115D01*
X0291662Y0035944D02*
D01*
X0290333Y0034444D02*
X0291662D01*
X0290333Y0032944D02*
X0291501D01*
X0290514Y0031444D02*
X0291501D01*
X0289764Y0029194D02*
Y0030694D01*
Y0029194D02*
Y0028944D01*
X028991Y002859D02*
X0290549Y0027951D01*
X0274803Y0028501D02*
Y0028937D01*
X027379Y0038751D02*
X027874Y0043701D01*
X0274807Y0037755D02*
Y0038005D01*
X0274806Y0035561D02*
X0274807Y0037755D01*
X0274806Y0035561D02*
D01*
X0273393Y0034812D02*
X0274056D01*
X0273393Y0033312D02*
X0275055D01*
X0273392Y0031812D02*
X0275055D01*
X0273392Y0030312D02*
X0274054D01*
X0274804Y0029561D02*
D01*
Y0029187D02*
Y0029561D01*
X0274803Y0028937D02*
X0274804Y0029187D01*
X0252604Y0036068D02*
X0254359Y0037824D01*
X0251543Y0036068D02*
D01*
D01*
X0250482Y0035008D02*
D01*
X0249175Y0034194D02*
X0249422Y0033947D01*
X0248114Y0033133D02*
X0248361Y0032886D01*
X0246971Y0032155D02*
X02473Y0031826D01*
X024591Y0031095D02*
X024624Y0030765D01*
X0246063Y0029528D02*
X024624Y0029704D01*
X0244488Y0027953D02*
X0246063Y0029528D01*
X0255593Y003937D02*
Y0080255D01*
Y003937D02*
D01*
X0276247Y0090701D02*
X0278186Y0088763D01*
G54D112*
X0527559Y0267717D02*
D01*
X0527878Y026806*
X0528174Y0268424*
X0528443Y0268808*
X0528684Y026921*
X0528897Y0269628*
X052908Y027006*
X0529233Y0270504*
X0529355Y0270957*
X0529444Y0271417*
X0529501Y0271883*
X0529526Y0272351*
X0529528Y0272469*
Y027559D02*
D01*
X0529516Y0275921*
X0529481Y0276251*
X0529424Y0276577*
X0529343Y0276899*
X0529241Y0277215*
X0529117Y0277522*
X0528971Y027782*
X0528805Y0278108*
X052862Y0278383*
X0528416Y0278644*
X0528194Y0278891*
X0528136Y0278951*
X0527261Y0279826D02*
D01*
X052726Y0279826*
X052726Y0279826*
X052726Y0279826*
X052726Y0279826*
X052726Y0279827*
X046159Y0293331D02*
D01*
X0461079Y0293807*
X0460537Y0294246*
X0459965Y0294646*
X0459367Y0295006*
X0458745Y0295322*
X0458102Y0295595*
X0457442Y0295822*
X0456768Y0296003*
X0456083Y0296136*
X045539Y0296221*
X0454693Y0296258*
X0454519Y029626*
X0479354Y0275567D02*
D01*
X0479864Y027509*
X0480406Y0274651*
X0480978Y0274251*
X0481576Y0273891*
X0482198Y0273575*
X0482841Y0273302*
X0483501Y0273075*
X0484175Y0272894*
X048486Y0272761*
X0485553Y0272676*
X048625Y0272639*
X0486426Y0272638*
X0520852D02*
D01*
X0521086Y0272646*
X0521319Y027267*
X052155Y0272711*
X0521778Y0272768*
X0522001Y027284*
X0522218Y0272928*
X0522429Y0273031*
X0522632Y0273148*
X0522826Y0273279*
X0523011Y0273424*
X0523186Y0273581*
X0523228Y0273622*
X0462575Y0297268D02*
D01*
X0462064Y0297744*
X0461522Y0298183*
X046095Y0298583*
X0460352Y0298943*
X045973Y0299259*
X0459087Y0299532*
X0458427Y0299759*
X0457753Y029994*
X0457068Y0300073*
X0456375Y0300158*
X0455678Y0300195*
X0455504Y0300197*
X028367Y029626D02*
D01*
X0282972Y0296235*
X0282278Y0296162*
X028159Y0296041*
X0280913Y0295872*
X0280249Y0295656*
X0279602Y0295395*
X0278975Y0295089*
X027837Y029474*
X0277792Y029435*
X0277242Y029392*
X0276723Y0293453*
X0276599Y0293331*
X0273646Y0228323D02*
D01*
X0274156Y0227846*
X0274698Y0227407*
X027527Y0227007*
X0275868Y0226647*
X027649Y0226331*
X0277133Y0226058*
X0277793Y0225831*
X0278467Y022565*
X0279152Y0225517*
X0279845Y0225432*
X0280542Y0225395*
X0280717Y0225394*
X052726Y0279827D02*
D01*
X0526968Y0280098*
X0526659Y0280348*
X0526333Y0280577*
X0525992Y0280782*
X0525637Y0280962*
X0525271Y0281118*
X0524894Y0281247*
X052451Y028135*
X0524119Y0281426*
X0523724Y0281475*
X0523326Y0281495*
X0523228Y0281496*
X0481323Y0270645D02*
D01*
X0481833Y0270168*
X0482375Y0269729*
X0482947Y0269329*
X0483545Y0268969*
X0484167Y0268653*
X048481Y026838*
X048547Y0268153*
X0486144Y0267972*
X0486829Y0267839*
X0487522Y0267754*
X0488219Y0267717*
X0488394Y0267717*
X0460606Y0291362D02*
D01*
X0460095Y0291838*
X0459553Y0292277*
X0458981Y0292677*
X0458383Y0293037*
X0457761Y0293353*
X0457118Y0293626*
X0456458Y0293853*
X0455784Y0294034*
X0455099Y0294167*
X0454406Y0294252*
X0453709Y0294289*
X0453535Y0294291*
X0396485D02*
D01*
X0396016Y0294274*
X0395549Y0294225*
X0395087Y0294144*
X0394632Y029403*
X0394186Y0293885*
X0393751Y0293709*
X0393329Y0293504*
X0392923Y0293269*
X0392534Y0293007*
X0392164Y0292718*
X0391816Y0292404*
X0391732Y0292323*
X0386787Y0287378D02*
D01*
X038631Y0286867*
X0385871Y0286325*
X0385471Y0285753*
X0385111Y0285155*
X0384795Y0284533*
X0384522Y028389*
X0384295Y028323*
X0384114Y0282556*
X0383981Y0281871*
X0383896Y0281178*
X0383859Y0280481*
X0383858Y0280307*
X0380929Y024215D02*
D01*
X0381405Y024266*
X0381844Y0243202*
X0382244Y0243774*
X0382604Y0244372*
X038292Y0244994*
X0383193Y0245637*
X038342Y0246297*
X0383601Y0246971*
X0383734Y0247656*
X0383819Y0248349*
X0383856Y0249046*
X0383858Y0249221*
X0360031Y0225394D02*
D01*
X0360728Y0225418*
X0361422Y0225491*
X036211Y0225612*
X0362787Y0225781*
X0363451Y0225997*
X0364098Y0226258*
X0364725Y0226564*
X036533Y0226913*
X0365908Y0227303*
X0366458Y0227733*
X0366977Y02282*
X0367102Y0228323*
X048211Y0277732D02*
D01*
X048262Y0277255*
X0483162Y0276816*
X0483734Y0276416*
X0484332Y0276056*
X0484954Y027574*
X0485597Y0275467*
X0486257Y027524*
X0486931Y0275059*
X0487616Y0274926*
X0488309Y0274841*
X0489006Y0274804*
X0489182Y0274803*
X0269366Y0286098D02*
D01*
X0268889Y0285587*
X026845Y0285045*
X026805Y0284473*
X026769Y0283875*
X0267374Y0283253*
X0267101Y028261*
X0266874Y028195*
X0266693Y0281276*
X026656Y0280591*
X0266475Y0279898*
X0266438Y0279201*
X0266437Y0279027*
X0435031Y017815D02*
D01*
X0435728Y0178174*
X0436422Y0178247*
X043711Y0178368*
X0437787Y0178537*
X0438451Y0178753*
X0439098Y0179014*
X0439725Y017932*
X044033Y0179669*
X0440908Y0180059*
X0441458Y0180489*
X0441977Y0180956*
X0442102Y0181079*
X0443922Y0182898D02*
D01*
X0444398Y0183408*
X0444837Y018395*
X0445237Y0184522*
X0445597Y018512*
X0445913Y0185742*
X0446186Y0186385*
X0446413Y0187045*
X0446594Y0187719*
X0446727Y0188404*
X0446812Y0189097*
X0446849Y0189794*
X044685Y0189969*
X0449779Y0289346D02*
D01*
X0449302Y0288835*
X0448863Y0288293*
X0448463Y0287721*
X0448103Y0287123*
X0447787Y0286501*
X0447514Y0285858*
X0447287Y0285198*
X0447106Y0284524*
X0446973Y0283839*
X0446888Y0283146*
X0446851Y0282449*
X044685Y0282275*
X0436864Y0175652D02*
D01*
X0437561Y0175676*
X0438255Y0175749*
X0438943Y017587*
X043962Y0176039*
X0440284Y0176255*
X0440931Y0176516*
X0441558Y0176822*
X0442163Y0177171*
X0442741Y0177561*
X0443291Y0177991*
X044381Y0178458*
X0443935Y0178581*
X0446874Y018152D02*
D01*
X044735Y018203*
X0447789Y0182572*
X0448189Y0183144*
X0448549Y0183742*
X0448865Y0184364*
X0449138Y0185007*
X0449365Y0185667*
X0449546Y0186341*
X0449679Y0187026*
X0449764Y0187719*
X0449801Y0188416*
X0449803Y0188591*
X0564921Y0289615D02*
D01*
X0564945Y0288917*
X0565018Y0288223*
X0565139Y0287535*
X0565308Y0286858*
X0565524Y0286194*
X0565785Y0285547*
X0566091Y028492*
X056644Y0284315*
X056683Y0283737*
X056726Y0283187*
X0567727Y0282668*
X056785Y0282543*
X052637Y015748D02*
D01*
X0527067Y0157504*
X0527761Y0157577*
X0528449Y0157698*
X0529126Y0157867*
X052979Y0158083*
X0530437Y0158344*
X0531064Y015865*
X0531669Y0158999*
X0532247Y0159389*
X0532797Y0159819*
X0533316Y0160286*
X0533441Y0160409*
X0578764Y0205732D02*
D01*
X057924Y0206242*
X0579679Y0206784*
X0580079Y0207356*
X0580439Y0207954*
X0580755Y0208576*
X0581028Y0209219*
X0581255Y0209879*
X0581436Y0210553*
X0581569Y0211238*
X0581654Y0211931*
X0581691Y0212628*
X0581693Y0212804*
X0525793Y0160433D02*
D01*
X0526256Y0160449*
X0526717Y0160497*
X0527173Y0160578*
X0527623Y016069*
X0528064Y0160833*
X0528493Y0161007*
X052891Y016121*
X0529311Y0161441*
X0529695Y0161701*
X0530061Y0161986*
X0530405Y0162296*
X0530488Y0162378*
X0575811Y0207701D02*
D01*
X0576287Y0208211*
X0576726Y0208753*
X0577126Y0209325*
X0577486Y0209923*
X0577802Y0210545*
X0578075Y0211188*
X0578302Y0211848*
X0578483Y0212522*
X0578616Y0213207*
X0578701Y02139*
X0578738Y0214597*
X057874Y0214772*
X0581693Y0270464D02*
D01*
X0581668Y0271161*
X0581595Y0271855*
X0581474Y0272543*
X0581305Y027322*
X0581089Y0273884*
X0580828Y0274531*
X0580522Y0275158*
X0580173Y0275763*
X0579783Y0276341*
X0579353Y0276891*
X0578886Y027741*
X0578764Y0277535*
X057874Y0267511D02*
D01*
X0578715Y0268208*
X0578642Y0268902*
X0578521Y026959*
X0578352Y0270267*
X0578136Y0270931*
X0577875Y0271578*
X0577569Y0272205*
X057722Y027281*
X057683Y0273388*
X05764Y0273938*
X0575933Y0274457*
X0575811Y0274583*
X052249Y0162833D02*
D01*
X0523084Y0162853*
X0523676Y0162915*
X0524262Y0163019*
X052484Y0163163*
X0525406Y0163347*
X0525958Y016357*
X0526493Y0163831*
X0527008Y0164128*
X0527502Y0164461*
X0527971Y0164827*
X0528413Y0165226*
X0528519Y0165331*
X0572858Y0209669D02*
D01*
X0573334Y0210179*
X0573773Y0210721*
X0574173Y0211293*
X0574533Y0211891*
X0574849Y0212513*
X0575122Y0213156*
X0575349Y0213816*
X057553Y021449*
X0575663Y0215175*
X0575748Y0215868*
X0575785Y0216565*
X0575787Y0216741*
Y0265543D02*
D01*
X0575762Y026624*
X0575689Y0266934*
X0575568Y0267622*
X0575399Y0268299*
X0575183Y0268963*
X0574922Y026961*
X0574616Y0270237*
X0574267Y0270842*
X0573877Y027142*
X0573447Y027197*
X057298Y0272489*
X0572858Y0272614*
X0520464Y0165354D02*
D01*
X0521161Y0165378*
X0521855Y0165451*
X0522543Y0165572*
X052322Y0165741*
X0523884Y0165957*
X0524531Y0166218*
X0525158Y0166524*
X0525763Y0166873*
X0526341Y0167263*
X0526891Y0167693*
X052741Y016816*
X0527535Y0168283*
X0569906Y0210654D02*
D01*
X0570382Y0211164*
X0570821Y0211706*
X0571221Y0212278*
X0571581Y0212876*
X0571897Y0213498*
X057217Y0214141*
X0572397Y0214801*
X0572578Y0215475*
X0572711Y021616*
X0572796Y0216853*
X0572833Y021755*
X0572835Y0217725*
Y0263496D02*
D01*
X057281Y0264193*
X0572737Y0264887*
X0572616Y0265575*
X0572447Y0266252*
X0572231Y0266916*
X057197Y0267563*
X0571664Y026819*
X0571315Y0268795*
X0570925Y0269373*
X0570495Y0269923*
X0570028Y0270442*
X0569906Y0270567*
X0503937Y041437D02*
X0505905Y0416339D01*
X0237205Y0267717D02*
Y0278543D01*
X0265748Y0307087D02*
X0448819D01*
X0237205Y0278543D02*
X0265748Y0307087D01*
X0268701Y0305118D02*
X0449803D01*
X024311Y0267748D02*
Y0279528D01*
X0268701Y0305118*
X05Y0358268D02*
Y042815D01*
X0448819Y0307087D02*
X05Y0358268D01*
X0449803Y0305118D02*
X0503937Y0359252D01*
Y041437*
X05Y042815D02*
X0505905Y0434055D01*
X0525748*
X0533622Y0426181*
X0529528Y0272469D02*
Y027559D01*
X052726Y0279827D02*
X0527261Y0279826D01*
X0528136Y0278951*
X0488394Y0267717D02*
X0527559D01*
X0486426Y0272638D02*
X0520852D01*
X046159Y0293331D02*
X0479354Y0275567D01*
X0279528Y0300197D02*
X0455504D01*
X0262598Y0283268D02*
X0279528Y0300197D01*
X028367Y029626D02*
X0454519D01*
X0272638Y0229331D02*
X0273646Y0228323D01*
X0286024Y0229232D02*
Y0268307D01*
X030115Y0283433*
Y0291307*
X028248Y0231299D02*
Y0268701D01*
X0294341Y0280561*
Y0291289*
X0280512Y0229331D02*
X028248Y0231299D01*
X0460606Y0291362D02*
X0481323Y0270645D01*
X0396485Y0294291D02*
X0453535D01*
X0386787Y0287378D02*
X0391732Y0292323D01*
X0383858Y0249221D02*
Y0280307D01*
X0367102Y0228323D02*
X0380929Y024215D01*
X0280717Y0225394D02*
X0360031D01*
X0449803Y0188591D02*
Y0284449D01*
X044685Y0189969D02*
Y0282275D01*
X0462575Y0297268D02*
X048211Y0277732D01*
X0266437Y0229134D02*
Y0279027D01*
X0269366Y0286098D02*
X0276599Y0293331D01*
X0262598Y0229134D02*
Y0283268D01*
X0489182Y0274803D02*
X0492913D01*
X0401575Y017815D02*
X0435031D01*
X0442102Y0181079D02*
X0443922Y0182898D01*
X0449779Y0289346D02*
X0449803Y028937D01*
X0401461Y0175652D02*
X0436864D01*
X0443935Y0178581D02*
X0446874Y018152D01*
X056785Y0282543D02*
X0575811Y0274583D01*
X0564921Y0289615D02*
Y0290394D01*
X0533441Y0160409D02*
X0578764Y0205732D01*
X0530488Y0162378D02*
X0575811Y0207701D01*
X0401575Y015748D02*
X052637D01*
X0570866Y0285433D02*
X0578764Y0277535D01*
X0581693Y0212804D02*
Y0270464D01*
X0401575Y0160433D02*
X0525793D01*
X057874Y0214772D02*
Y0267511D01*
X0401575Y0162833D02*
X052249D01*
X0528519Y0165331D02*
X0572858Y0209669D01*
X0564961Y0280512D02*
X0572858Y0272614D01*
X0575787Y0216741D02*
Y0265543D01*
X0401575Y0165354D02*
X0520464D01*
X0527535Y0168283D02*
X0569906Y0210654D01*
X0564921Y0275551D02*
X0569906Y0270567D01*
X0572835Y0217725D02*
Y0263496D01*
G54D113*
X0523622Y0300197D02*
Y0426181D01*
Y0300197D02*
X0525591Y0298228D01*
G54D122*
X0523622Y0426181D03*
X0533622D03*
G54D126*
X0505905Y0416339D03*
X024311Y0267748D03*
X0237205Y0267717D03*
X0525591Y0298228D03*
X0595472Y0145669D03*
X0597441D03*
Y0141732D03*
Y0143701D03*
X0272638Y0229331D03*
X030115Y0291307D03*
X0294341Y0291289D03*
X0280512Y0229331D03*
X0523228Y0281496D03*
Y0273622D03*
X0286024Y0229232D03*
X0266437Y0229134D03*
X0262598D03*
X0492913Y0274803D03*
X0564921Y0290394D03*
X0570866Y0285433D03*
X0401575Y015748D03*
X0449803Y028937D03*
Y0284449D03*
X0401461Y0175652D03*
X0401575Y017815D03*
Y0165354D03*
Y0162833D03*
Y0160433D03*
X0564961Y0280512D03*
X0564921Y0275551D03*
X0276772Y0097638D03*
X0274016D03*
X0282677Y0079528D03*
X0269291D03*
X0264961Y0097638D03*
X0262205D03*
X0266535Y0079528D03*
X0279921D03*
X0261024Y0027953D03*
X0257874D03*
X0274882Y0028231D03*
X0290549Y0027951D03*
X0277953Y0027953D03*
X0293701D03*
X0241339D03*
X0244488D03*
G54D128*
X0370669Y0072933D03*
G54D130*
X0597638Y0092716D02*
Y0143701D01*
X0597539Y0143799D02*
X0597638Y0143701D01*
X0597539Y0143799D02*
Y0145571D01*
X0597441Y0145669D02*
X0597539Y0145571D01*
X0577854Y0072933D02*
X0597638Y0092716D01*
X0370669Y0072933D02*
X0577854D01*
M02*